#ISCELL
  mstr_misc dns *
  *
#ISCELL
  mstr_symbols design_note *
  *
#ISCELL
  mstr_symbols intel_corp_bpage *
  *
#ISCELL
  mstr_standard offpage *
  page223_i1
#ISCELL
  mstr_standard offpage *
  page223_i10
#ISCELL
  mstr_standard offpage *
  page223_i11
#CELL
  mstr_discrete cap *
  page223_i12
#CELL
  mstr_discrete res *
  page223_i13
#CELL
  mstr_discrete res *
  page223_i14
#CELL
  w_hdl sc22p50v2jn-4gp *
  page223_i15
#CELL
  mstr_discrete res *
  page223_i16
#CELL
  w_hdl sc22p50v2jn-4gp *
  page223_i17
#CELL
  mstr_discrete res *
  page223_i18
#CELL
  mstr_discrete res *
  page223_i19
#ISCELL
  mstr_standard offpage *
  page223_i2
#ISCELL
  mstr_symbols pvccio_cpu1 *
  page223_i21
#ISCELL
  mstr_symbols gnd *
  page223_i22
#ISCELL
  mstr_symbols gnd *
  page223_i23
#ISCELL
  mstr_symbols gnd *
  page223_i24
#ISCELL
  mstr_symbols gnd *
  page223_i25
#CELL
  mstr_discrete cap *
  page223_i27
#ISCELL
  mstr_symbols gnd *
  page223_i28
#ISCELL
  mstr_symbols gnd *
  page223_i29
#ISCELL
  mstr_standard offpage *
  page223_i3
#CELL
  mstr_discrete res *
  page223_i31
#CELL
  mstr_discrete res *
  page223_i32
#ISCELL
  mstr_symbols p3v3_stby *
  page223_i33
#ISCELL
  mstr_symbols gnd *
  page223_i34
#CELL
  dev_discrete cap_a *
  page223_i35
#CELL
  dev_discrete cap_a *
  page223_i36
#ISCELL
  mstr_symbols gnd *
  page223_i37
#ISCELL
  mstr_symbols gnd *
  page223_i38
#ISCELL
  mstr_symbols gnd *
  page223_i39
#ISCELL
  mstr_standard offpage *
  page223_i4
#CELL
  mstr_discrete cap *
  page223_i40
#CELL
  mstr_discrete res *
  page223_i41
#CELL
  dev_discrete cap_a *
  page223_i43
#CELL
  dev_discrete cap_a *
  page223_i44
#CELL
  mstr_discrete res *
  page223_i45
#CELL
  mstr_discrete res *
  page223_i48
#CELL
  mstr_discrete res *
  page223_i49
#ISCELL
  mstr_standard offpage *
  page223_i5
#CELL
  mstr_discrete res *
  page223_i50
#ISCELL
  mstr_standard offpage *
  page223_i51
#ISCELL
  mstr_symbols p3v3_stby *
  page223_i52
#CELL
  mstr_discrete res *
  page223_i53
#CELL
  mstr_discrete res *
  page223_i54
#CELL
  mstr_discrete res *
  page223_i55
#CELL
  mstr_discrete res *
  page223_i57
#ISCELL
  mstr_symbols pvccio_cpu1 *
  page223_i58
#ISCELL
  mstr_standard offpage *
  page223_i59
#ISCELL
  mstr_standard offpage *
  page223_i6
#ISCELL
  mstr_standard offpage *
  page223_i60
#ISCELL
  mstr_standard offpage *
  page223_i61
#ISCELL
  mstr_standard offpage *
  page223_i62
#ISCELL
  mstr_standard offpage *
  page223_i63
#ISCELL
  mstr_standard offpage *
  page223_i64
#ISCELL
  mstr_standard offpage *
  page223_i65
#ISCELL
  mstr_standard offpage *
  page223_i66
#ISCELL
  mstr_standard offpage *
  page223_i67
#ISCELL
  mstr_standard offpage *
  page223_i68
#CELL
  mstr_controller pxm1310b *
  page223_i69
#ISCELL
  mstr_standard offpage *
  page223_i7
#CELL
  mstr_discrete res *
  page223_i70
#CELL
  mstr_discrete res *
  page223_i73
#CELL
  mstr_discrete res *
  page223_i74
#CELL
  mstr_discrete res *
  page223_i75
#CELL
  mstr_discrete res *
  page223_i76
#ISCELL
  mstr_standard offpage *
  page223_i8
#ISCELL
  mstr_standard offpage *
  page223_i9
